FILE_TYPE = CONNECTIVITY;
{Allegro Design Entry HDL 17.4-2019 S026 (4007227) 1/17/2022}
"PAGE_NUMBER" = 211;
0"NC";
1"DELTA_L_85_5INCH_IN2_DN"CDS_PHYS_NET_NAME"DELTA_L_85_5INCH_IN2_DN";
2"DELTA_L_85_5INCH_IN5_DN"CDS_PHYS_NET_NAME"DELTA_L_85_5INCH_IN5_DN";
3"DELTA_L_85_5INCH_IN6_DP"CDS_PHYS_NET_NAME"DELTA_L_85_5INCH_IN6_DP";
4"DELTA_L_85_5INCH_IN6_DN"CDS_PHYS_NET_NAME"DELTA_L_85_5INCH_IN6_DN";
5"DELTA_L_85_5INCH_BOT_DN"CDS_PHYS_NET_NAME"DELTA_L_85_5INCH_BOT_DN";
6"DELTA_L_85_5INCH_BOT_DP"CDS_PHYS_NET_NAME"DELTA_L_85_5INCH_BOT_DP";
7"DELTA_L_85_5INCH_IN1_DN"CDS_PHYS_NET_NAME"DELTA_L_85_5INCH_IN1_DN";
8"DELTA_L_85_5INCH_IN1_DP"CDS_PHYS_NET_NAME"DELTA_L_85_5INCH_IN1_DP";
9"DELTA_L_85_5INCH_IN2_DP"CDS_PHYS_NET_NAME"DELTA_L_85_5INCH_IN2_DP";
10"DELTA_L_85_5INCH_IN3_DN"CDS_PHYS_NET_NAME"DELTA_L_85_5INCH_IN3_DN";
11"DELTA_L_85_5INCH_IN4_DN"CDS_PHYS_NET_NAME"DELTA_L_85_5INCH_IN4_DN";
12"DELTA_L_85_5INCH_IN4_DP"CDS_PHYS_NET_NAME"DELTA_L_85_5INCH_IN4_DP";
13"DELTA_L_85_5INCH_IN5_DP"CDS_PHYS_NET_NAME"DELTA_L_85_5INCH_IN5_DP";
14"DELTA_L_85_5INCH_TOP_DP"CDS_PHYS_NET_NAME"DELTA_L_85_5INCH_TOP_DP";
15"DELTA_L_85_5INCH_TOP_DN"CDS_PHYS_NET_NAME"DELTA_L_85_5INCH_TOP_DN";
16"DELTA_L_85_10INCH_TOP_DN"CDS_PHYS_NET_NAME"DELTA_L_85_10INCH_TOP_DN";
17"DELTA_L_85_10INCH_TOP_DP"CDS_PHYS_NET_NAME"DELTA_L_85_10INCH_TOP_DP";
18"DELTA_L_85_10INCH_BOT_DN"CDS_PHYS_NET_NAME"DELTA_L_85_10INCH_BOT_DN";
19"DELTA_L_85_10INCH_BOT_DP"CDS_PHYS_NET_NAME"DELTA_L_85_10INCH_BOT_DP";
20"DELTA_L_85_10INCH_IN1_DN"CDS_PHYS_NET_NAME"DELTA_L_85_10INCH_IN1_DN";
21"DELTA_L_85_10INCH_IN1_DP"CDS_PHYS_NET_NAME"DELTA_L_85_10INCH_IN1_DP";
22"DELTA_L_85_10INCH_IN2_DN"CDS_PHYS_NET_NAME"DELTA_L_85_10INCH_IN2_DN";
23"DELTA_L_85_10INCH_IN2_DP"CDS_PHYS_NET_NAME"DELTA_L_85_10INCH_IN2_DP";
24"DELTA_L_85_10INCH_IN3_DP"CDS_PHYS_NET_NAME"DELTA_L_85_10INCH_IN3_DP";
25"DELTA_L_85_10INCH_IN3_DN"CDS_PHYS_NET_NAME"DELTA_L_85_10INCH_IN3_DN";
26"DELTA_L_GND_1\g";
27"DELTA_L_GND_1\g";
28"DELTA_L_GND_1\g";
29"DELTA_L_GND_1\g";
30"DELTA_L_GND_1\g";
31"DELTA_L_GND_1\g";
32"DELTA_L_GND_1\g";
33"DELTA_L_GND_1\g";
34"DELTA_L_GND_1\g";
35"DELTA_L_GND_1\g";
36"DELTA_L_GND_1\g";
37"DELTA_L_GND_1\g";
38"DELTA_L_GND_1\g";
39"DELTA_L_GND_1\g";
40"DELTA_L_GND_1\g";
41"DELTA_L_GND_1\g";
42"DELTA_L_GND_1\g";
43"DELTA_L_GND_1\g";
44"DELTA_L_GND_1\g";
45"DELTA_L_GND_1\g";
46"DELTA_L_GND_1\g";
47"DELTA_L_GND_1\g";
48"DELTA_L_GND_1\g";
49"DELTA_L_GND_1\g";
50"DELTA_L_GND_1\g";
51"DELTA_L_GND_1\g";
52"DELTA_L_GND_1\g";
53"DELTA_L_GND_1\g";
54"DELTA_L_GND_1\g";
55"DELTA_L_GND_1\g";
56"DELTA_L_GND_1\g";
57"DELTA_L_85_10INCH_IN6_DP"CDS_PHYS_NET_NAME"DELTA_L_85_10INCH_IN6_DP";
58"DELTA_L_85_10INCH_IN6_DN"CDS_PHYS_NET_NAME"DELTA_L_85_10INCH_IN6_DN";
59"DELTA_L_85_5INCH_IN3_DP"CDS_PHYS_NET_NAME"DELTA_L_85_5INCH_IN3_DP";
60"DELTA_L_85_10INCH_IN4_DN"CDS_PHYS_NET_NAME"DELTA_L_85_10INCH_IN4_DN";
61"DELTA_L_GND_1\g";
62"DELTA_L_85_10INCH_IN5_DP"CDS_PHYS_NET_NAME"DELTA_L_85_10INCH_IN5_DP";
63"DELTA_L_85_10INCH_IN5_DN"CDS_PHYS_NET_NAME"DELTA_L_85_10INCH_IN5_DN";
64"DELTA_L_85_10INCH_IN4_DP"CDS_PHYS_NET_NAME"DELTA_L_85_10INCH_IN4_DP";
%"UNIVERSAL_GND"
"1","(-8125,1975)","0","pure_quanta_power","I1";
;
HDL_POWER"DELTA_L_GND_1"
CDS_LIB"pure_quanta_power";
"A"29;
%"UNIVERSAL_GND"
"1","(-5175,550)","0","pure_quanta_power","I16";
;
HDL_POWER"DELTA_L_GND_1"
CDS_LIB"pure_quanta_power";
"A"30;
%"UNIVERSAL_GND"
"1","(-5225,1325)","0","pure_quanta_power","I19";
;
HDL_POWER"DELTA_L_GND_1"
CDS_LIB"pure_quanta_power";
"A"31;
%"UNIVERSAL_GND"
"1","(-8150,2725)","0","pure_quanta_power","I2";
;
HDL_POWER"DELTA_L_GND_1"
CDS_LIB"pure_quanta_power";
"A"32;
%"UNIVERSAL_GND"
"1","(-5250,1975)","0","pure_quanta_power","I20";
;
HDL_POWER"DELTA_L_GND_1"
CDS_LIB"pure_quanta_power";
"A"33;
%"UNIVERSAL_GND"
"1","(-5375,2675)","0","pure_quanta_power","I22";
;
HDL_POWER"DELTA_L_GND_1"
CDS_LIB"pure_quanta_power";
"A"34;
%"UNIVERSAL_GND"
"1","(-5375,3400)","0","pure_quanta_power","I25";
;
HDL_POWER"DELTA_L_GND_1"
CDS_LIB"pure_quanta_power";
"A"35;
%"UNIVERSAL_GND"
"1","(-5350,4150)","0","pure_quanta_power","I26";
;
HDL_POWER"DELTA_L_GND_1"
CDS_LIB"pure_quanta_power";
"A"36;
%"UNIVERSAL_GND"
"1","(-8125,3400)","0","pure_quanta_power","I3";
;
HDL_POWER"DELTA_L_GND_1"
CDS_LIB"pure_quanta_power";
"A"37;
%"UNIVERSAL_GND"
"1","(-5375,4875)","0","pure_quanta_power","I30";
;
HDL_POWER"DELTA_L_GND_1"
CDS_LIB"pure_quanta_power";
"A"38;
%"UNIVERSAL_GND"
"1","(-5375,5650)","0","pure_quanta_power","I32";
;
HDL_POWER"DELTA_L_GND_1"
CDS_LIB"pure_quanta_power";
"A"39;
%"UNIVERSAL_GND"
"1","(-4025,650)","0","pure_quanta_power","I33";
;
HDL_POWER"DELTA_L_GND_1"
CDS_LIB"pure_quanta_power";
"A"56;
%"UNIVERSAL_GND"
"1","(-4050,1200)","0","pure_quanta_power","I35";
;
HDL_POWER"DELTA_L_GND_1"
CDS_LIB"pure_quanta_power";
"A"55;
%"UNIVERSAL_GND"
"1","(-4100,2000)","0","pure_quanta_power","I37";
;
HDL_POWER"DELTA_L_GND_1"
CDS_LIB"pure_quanta_power";
"A"52;
%"UNIVERSAL_GND"
"1","(-4100,2775)","0","pure_quanta_power","I38";
;
HDL_POWER"DELTA_L_GND_1"
CDS_LIB"pure_quanta_power";
"A"26;
%"UNIVERSAL_GND"
"1","(-8125,4125)","0","pure_quanta_power","I4";
;
HDL_POWER"DELTA_L_GND_1"
CDS_LIB"pure_quanta_power";
"A"40;
%"UNIVERSAL_GND"
"1","(-4100,3425)","0","pure_quanta_power","I40";
;
HDL_POWER"DELTA_L_GND_1"
CDS_LIB"pure_quanta_power";
"A"28;
%"UNIVERSAL_GND"
"1","(-4050,4150)","0","pure_quanta_power","I42";
;
HDL_POWER"DELTA_L_GND_1"
CDS_LIB"pure_quanta_power";
"A"41;
%"UNIVERSAL_GND"
"1","(-1125,600)","0","pure_quanta_power","I45";
;
HDL_POWER"DELTA_L_GND_1"
CDS_LIB"pure_quanta_power";
"A"61;
%"UNIVERSAL_GND"
"1","(-1025,1375)","0","pure_quanta_power","I48";
;
HDL_POWER"DELTA_L_GND_1"
CDS_LIB"pure_quanta_power";
"A"54;
%"UNIVERSAL_GND"
"1","(-1025,2025)","0","pure_quanta_power","I49";
;
HDL_POWER"DELTA_L_GND_1"
CDS_LIB"pure_quanta_power";
"A"53;
%"UNIVERSAL_GND"
"1","(-8125,4875)","0","pure_quanta_power","I5";
;
HDL_POWER"DELTA_L_GND_1"
CDS_LIB"pure_quanta_power";
"A"42;
%"UNIVERSAL_GND"
"1","(-1075,2750)","0","pure_quanta_power","I51";
;
HDL_POWER"DELTA_L_GND_1"
CDS_LIB"pure_quanta_power";
"A"27;
%"UNIVERSAL_GND"
"1","(-1075,3425)","0","pure_quanta_power","I54";
;
HDL_POWER"DELTA_L_GND_1"
CDS_LIB"pure_quanta_power";
"A"43;
%"UNIVERSAL_GND"
"1","(-1050,4125)","0","pure_quanta_power","I55";
;
HDL_POWER"DELTA_L_GND_1"
CDS_LIB"pure_quanta_power";
"A"44;
%"UNIVERSAL_GND"
"1","(-4075,4875)","0","pure_quanta_power","I56";
;
HDL_POWER"DELTA_L_GND_1"
CDS_LIB"pure_quanta_power";
"A"45;
%"UNIVERSAL_GND"
"1","(-4075,5675)","0","pure_quanta_power","I58";
;
HDL_POWER"DELTA_L_GND_1"
CDS_LIB"pure_quanta_power";
"A"46;
%"UNIVERSAL_GND"
"1","(-8125,5700)","0","pure_quanta_power","I6";
;
HDL_POWER"DELTA_L_GND_1"
CDS_LIB"pure_quanta_power";
"A"47;
%"UNIVERSAL_GND"
"1","(-1200,4875)","0","pure_quanta_power","I61";
;
HDL_POWER"DELTA_L_GND_1"
CDS_LIB"pure_quanta_power";
"A"48;
%"UNIVERSAL_GND"
"1","(-975,5675)","0","pure_quanta_power","I63";
;
HDL_POWER"DELTA_L_GND_1"
CDS_LIB"pure_quanta_power";
"A"49;
%"PICOPROBE_BXA"
"1","(-7650,5775)","0","pure_quanta","I65";
;
LOCATION"J63"
SEC"1"
MATERIAL"EMPTY"
VALUE"DELTA-L 4.0"
PART_TYPE"SMLF"
NEEDS_NO_SIZE"TRUE"
SEC_TYPE""
CDS_LIB"pure_quanta"
CDS_LMAN_SYM_OUTLINE"-150,100,150,-100"
PART_NUMBER"TP33";
"1_P"
$PN"1"14;
"3_G"
$PN"3"47;
"2_N"
$PN"2"15;
%"PICOPROBE_BXA"
"1","(-5875,5825)","4","pure_quanta","I66";
;
LOCATION"J8069"
SEC"1"
MATERIAL"EMPTY"
VALUE"DELTA-L 4.0"
PART_TYPE"SMLF"
NEEDS_NO_SIZE"TRUE"
SEC_TYPE""
CDS_LMAN_SYM_OUTLINE"-150,100,150,-100"
CDS_LIB"pure_quanta"
PART_NUMBER"TP33";
"1_P"
$PN"1"15;
"3_G"
$PN"3"39;
"2_N"
$PN"2"14;
%"PICOPROBE_BXA"
"1","(-7650,5050)","0","pure_quanta","I67";
;
LOCATION"J64"
SEC"1"
VALUE"DELTA-L 4.0"
PART_TYPE"SMLF"
MATERIAL"EMPTY"
SEC_TYPE""
CDS_LIB"pure_quanta"
CDS_LMAN_SYM_OUTLINE"-150,100,150,-100"
NEEDS_NO_SIZE"TRUE"
PART_NUMBER"TP33";
"1_P"
$PN"1"6;
"3_G"
$PN"3"42;
"2_N"
$PN"2"5;
%"PICOPROBE_BXA"
"1","(-5875,5100)","4","pure_quanta","I68";
;
LOCATION"J70"
SEC"1"
VALUE"DELTA-L 4.0"
MATERIAL"EMPTY"
PART_TYPE"SMLF"
CDS_LIB"pure_quanta"
CDS_LMAN_SYM_OUTLINE"-150,100,150,-100"
SEC_TYPE""
NEEDS_NO_SIZE"TRUE"
PART_NUMBER"TP33";
"1_P"
$PN"1"5;
"3_G"
$PN"3"38;
"2_N"
$PN"2"6;
%"PICOPROBE_BXA"
"1","(-7675,4300)","0","pure_quanta","I69";
;
LOCATION"J65"
SEC"1"
MATERIAL"EMPTY"
VALUE"DELTA-L 4.0"
PART_TYPE"SMLF"
NEEDS_NO_SIZE"TRUE"
SEC_TYPE""
CDS_LMAN_SYM_OUTLINE"-150,100,150,-100"
CDS_LIB"pure_quanta"
PART_NUMBER"TP33";
"1_P"
$PN"1"8;
"3_G"
$PN"3"40;
"2_N"
$PN"2"7;
%"UNIVERSAL_GND"
"1","(-8100,1325)","0","pure_quanta_power","I7";
;
HDL_POWER"DELTA_L_GND_1"
CDS_LIB"pure_quanta_power";
"A"50;
%"PICOPROBE_BXA"
"1","(-5875,4350)","4","pure_quanta","I70";
;
LOCATION"J71"
SEC"1"
MATERIAL"EMPTY"
VALUE"DELTA-L 4.0"
PART_TYPE"SMLF"
NEEDS_NO_SIZE"TRUE"
SEC_TYPE""
CDS_LMAN_SYM_OUTLINE"-150,100,150,-100"
CDS_LIB"pure_quanta"
PART_NUMBER"TP33";
"1_P"
$PN"1"7;
"3_G"
$PN"3"36;
"2_N"
$PN"2"8;
%"PICOPROBE_BXA"
"1","(-7675,3575)","0","pure_quanta","I71";
;
LOCATION"J66"
SEC"1"
VALUE"DELTA-L 4.0"
MATERIAL"EMPTY"
PART_TYPE"SMLF"
CDS_LIB"pure_quanta"
CDS_LMAN_SYM_OUTLINE"-150,100,150,-100"
SEC_TYPE""
NEEDS_NO_SIZE"TRUE"
PART_NUMBER"TP33";
"1_P"
$PN"1"9;
"3_G"
$PN"3"37;
"2_N"
$PN"2"1;
%"PICOPROBE_BXA"
"1","(-5875,3625)","4","pure_quanta","I72";
;
LOCATION"J72"
SEC"1"
MATERIAL"EMPTY"
VALUE"DELTA-L 4.0"
PART_TYPE"SMLF"
CDS_LIB"pure_quanta"
CDS_LMAN_SYM_OUTLINE"-150,100,150,-100"
SEC_TYPE""
NEEDS_NO_SIZE"TRUE"
PART_NUMBER"TP33";
"1_P"
$PN"1"1;
"3_G"
$PN"3"35;
"2_N"
$PN"2"9;
%"PICOPROBE_BXA"
"1","(-7700,2900)","0","pure_quanta","I73";
;
LOCATION"J8067"
SEC"1"
MATERIAL"EMPTY"
VALUE"DELTA-L 4.0"
PART_TYPE"SMLF"
NEEDS_NO_SIZE"TRUE"
SEC_TYPE""
CDS_LMAN_SYM_OUTLINE"-150,100,150,-100"
CDS_LIB"pure_quanta"
PART_NUMBER"TP33";
"1_P"
$PN"1"59;
"3_G"
$PN"3"32;
"2_N"
$PN"2"10;
%"PICOPROBE_BXA"
"1","(-5825,2950)","4","pure_quanta","I74";
;
LOCATION"J73"
SEC"1"
VALUE"DELTA-L 4.0"
PART_TYPE"SMLF"
MATERIAL"EMPTY"
CDS_LIB"pure_quanta"
CDS_LMAN_SYM_OUTLINE"-150,100,150,-100"
SEC_TYPE""
NEEDS_NO_SIZE"TRUE"
PART_NUMBER"TP33";
"1_P"
$PN"1"10;
"3_G"
$PN"3"34;
"2_N"
$PN"2"59;
%"PICOPROBE_BXA"
"1","(-7650,2150)","0","pure_quanta","I75";
;
LOCATION"J8068"
SEC"1"
PART_TYPE"SMLF"
VALUE"DELTA-L 4.0"
MATERIAL"EMPTY"
NEEDS_NO_SIZE"TRUE"
SEC_TYPE""
CDS_LMAN_SYM_OUTLINE"-150,100,150,-100"
CDS_LIB"pure_quanta"
PART_NUMBER"TP33";
"1_P"
$PN"1"12;
"3_G"
$PN"3"29;
"2_N"
$PN"2"11;
%"PICOPROBE_BXA"
"1","(-5750,2200)","4","pure_quanta","I76";
;
LOCATION"J74"
SEC"1"
VALUE"DELTA-L 4.0"
PART_TYPE"SMLF"
MATERIAL"EMPTY"
CDS_LMAN_SYM_OUTLINE"-150,100,150,-100"
CDS_LIB"pure_quanta"
SEC_TYPE""
NEEDS_NO_SIZE"TRUE"
PART_NUMBER"TP33";
"1_P"
$PN"1"11;
"3_G"
$PN"3"33;
"2_N"
$PN"2"12;
%"PICOPROBE_BXA"
"1","(-7675,1450)","0","pure_quanta","I77";
;
LOCATION"J114"
SEC"1"
MATERIAL"EMPTY"
VALUE"DELTA-L 4.0"
PART_TYPE"SMLF"
NEEDS_NO_SIZE"TRUE"
SEC_TYPE""
CDS_LMAN_SYM_OUTLINE"-150,100,150,-100"
CDS_LIB"pure_quanta"
PART_NUMBER"TP33";
"1_P"
$PN"1"13;
"3_G"
$PN"3"50;
"2_N"
$PN"2"2;
%"PICOPROBE_BXA"
"1","(-5750,1500)","4","pure_quanta","I78";
;
LOCATION"J116"
SEC"1"
VALUE"DELTA-L 4.0"
PART_TYPE"SMLF"
MATERIAL"EMPTY"
NEEDS_NO_SIZE"TRUE"
SEC_TYPE""
CDS_LMAN_SYM_OUTLINE"-150,100,150,-100"
CDS_LIB"pure_quanta"
PART_NUMBER"TP33";
"1_P"
$PN"1"2;
"3_G"
$PN"3"31;
"2_N"
$PN"2"13;
%"PICOPROBE_BXA"
"1","(-7725,750)","0","pure_quanta","I79";
;
LOCATION"J115"
SEC"1"
VALUE"DELTA-L 4.0"
PART_TYPE"SMLF"
MATERIAL"EMPTY"
SEC_TYPE""
CDS_LIB"pure_quanta"
CDS_LMAN_SYM_OUTLINE"-150,100,150,-100"
NEEDS_NO_SIZE"TRUE"
PART_NUMBER"TP33";
"1_P"
$PN"1"3;
"3_G"
$PN"3"51;
"2_N"
$PN"2"4;
%"UNIVERSAL_GND"
"1","(-8075,575)","0","pure_quanta_power","I8";
;
HDL_POWER"DELTA_L_GND_1"
CDS_LIB"pure_quanta_power";
"A"51;
%"PICOPROBE_BXA"
"1","(-5725,800)","4","pure_quanta","I80";
;
LOCATION"J117"
SEC"1"
PART_TYPE"SMLF"
MATERIAL"EMPTY"
VALUE"DELTA-L 4.0"
SEC_TYPE""
CDS_LIB"pure_quanta"
CDS_LMAN_SYM_OUTLINE"-150,100,150,-100"
NEEDS_NO_SIZE"TRUE"
PART_NUMBER"TP33";
"1_P"
$PN"1"4;
"3_G"
$PN"3"30;
"2_N"
$PN"2"3;
%"PICOPROBE_BXA"
"1","(-3525,5800)","0","pure_quanta","I81";
;
LOCATION"J75"
SEC"1"
PART_TYPE"SMLF"
VALUE"DELTA-L 4.0"
MATERIAL"EMPTY"
CDS_LIB"pure_quanta"
CDS_LMAN_SYM_OUTLINE"-150,100,150,-100"
SEC_TYPE""
NEEDS_NO_SIZE"TRUE"
PART_NUMBER"TP33";
"1_P"
$PN"1"17;
"3_G"
$PN"3"46;
"2_N"
$PN"2"16;
%"PICOPROBE_BXA"
"1","(-1625,5850)","4","pure_quanta","I82";
;
LOCATION"J81"
SEC"1"
MATERIAL"EMPTY"
VALUE"DELTA-L 4.0"
PART_TYPE"SMLF"
CDS_LIB"pure_quanta"
CDS_LMAN_SYM_OUTLINE"-150,100,150,-100"
SEC_TYPE""
NEEDS_NO_SIZE"TRUE"
PART_NUMBER"TP33";
"1_P"
$PN"1"16;
"3_G"
$PN"3"49;
"2_N"
$PN"2"17;
%"PICOPROBE_BXA"
"1","(-3575,5050)","0","pure_quanta","I83";
;
LOCATION"J76"
SEC"1"
PART_TYPE"SMLF"
VALUE"DELTA-L 4.0"
MATERIAL"EMPTY"
NEEDS_NO_SIZE"TRUE"
SEC_TYPE""
CDS_LMAN_SYM_OUTLINE"-150,100,150,-100"
CDS_LIB"pure_quanta"
PART_NUMBER"TP33";
"1_P"
$PN"1"19;
"3_G"
$PN"3"45;
"2_N"
$PN"2"18;
%"PICOPROBE_BXA"
"1","(-1625,5100)","4","pure_quanta","I84";
;
LOCATION"J82"
SEC"1"
MATERIAL"EMPTY"
VALUE"DELTA-L 4.0"
PART_TYPE"SMLF"
NEEDS_NO_SIZE"TRUE"
SEC_TYPE""
CDS_LMAN_SYM_OUTLINE"-150,100,150,-100"
CDS_LIB"pure_quanta"
PART_NUMBER"TP33";
"1_P"
$PN"1"18;
"3_G"
$PN"3"48;
"2_N"
$PN"2"19;
%"PICOPROBE_BXA"
"1","(-3525,4325)","0","pure_quanta","I85";
;
LOCATION"J77"
SEC"1"
PART_TYPE"SMLF"
VALUE"DELTA-L 4.0"
MATERIAL"EMPTY"
CDS_LIB"pure_quanta"
CDS_LMAN_SYM_OUTLINE"-150,100,150,-100"
SEC_TYPE""
NEEDS_NO_SIZE"TRUE"
PART_NUMBER"TP33";
"1_P"
$PN"1"21;
"3_G"
$PN"3"41;
"2_N"
$PN"2"20;
%"PICOPROBE_BXA"
"1","(-1675,4375)","4","pure_quanta","I86";
;
LOCATION"J83"
SEC"1"
MATERIAL"EMPTY"
VALUE"DELTA-L 4.0"
PART_TYPE"SMLF"
CDS_LIB"pure_quanta"
CDS_LMAN_SYM_OUTLINE"-150,100,150,-100"
SEC_TYPE""
NEEDS_NO_SIZE"TRUE"
PART_NUMBER"TP33";
"1_P"
$PN"1"20;
"3_G"
$PN"3"44;
"2_N"
$PN"2"21;
%"PICOPROBE_BXA"
"1","(-3550,3575)","0","pure_quanta","I87";
;
LOCATION"J78"
SEC"1"
VALUE"DELTA-L 4.0"
MATERIAL"EMPTY"
PART_TYPE"SMLF"
NEEDS_NO_SIZE"TRUE"
SEC_TYPE""
CDS_LMAN_SYM_OUTLINE"-150,100,150,-100"
CDS_LIB"pure_quanta"
PART_NUMBER"TP33";
"1_P"
$PN"1"23;
"3_G"
$PN"3"28;
"2_N"
$PN"2"22;
%"PICOPROBE_BXA"
"1","(-1600,3625)","4","pure_quanta","I88";
;
LOCATION"J84"
SEC"1"
MATERIAL"EMPTY"
VALUE"DELTA-L 4.0"
PART_TYPE"SMLF"
NEEDS_NO_SIZE"TRUE"
SEC_TYPE""
CDS_LMAN_SYM_OUTLINE"-150,100,150,-100"
CDS_LIB"pure_quanta"
PART_NUMBER"TP33";
"1_P"
$PN"1"22;
"3_G"
$PN"3"43;
"2_N"
$PN"2"23;
%"PICOPROBE_BXA"
"1","(-3575,2900)","0","pure_quanta","I89";
;
LOCATION"J79"
SEC"1"
PART_TYPE"SMLF"
VALUE"DELTA-L 4.0"
MATERIAL"EMPTY"
CDS_LIB"pure_quanta"
CDS_LMAN_SYM_OUTLINE"-150,100,150,-100"
SEC_TYPE""
NEEDS_NO_SIZE"TRUE"
PART_NUMBER"TP33";
"1_P"
$PN"1"24;
"3_G"
$PN"3"26;
"2_N"
$PN"2"25;
%"PICOPROBE_BXA"
"1","(-1625,2950)","4","pure_quanta","I90";
;
LOCATION"J85"
SEC"1"
MATERIAL"EMPTY"
VALUE"DELTA-L 4.0"
PART_TYPE"SMLF"
CDS_LIB"pure_quanta"
CDS_LMAN_SYM_OUTLINE"-150,100,150,-100"
SEC_TYPE""
NEEDS_NO_SIZE"TRUE"
PART_NUMBER"TP33";
"1_P"
$PN"1"25;
"3_G"
$PN"3"27;
"2_N"
$PN"2"24;
%"PICOPROBE_BXA"
"1","(-3525,2150)","0","pure_quanta","I91";
;
LOCATION"J80"
SEC"1"
MATERIAL"EMPTY"
VALUE"DELTA-L 4.0"
PART_TYPE"SMLF"
CDS_LIB"pure_quanta"
CDS_LMAN_SYM_OUTLINE"-150,100,150,-100"
SEC_TYPE""
NEEDS_NO_SIZE"TRUE"
PART_NUMBER"TP33";
"1_P"
$PN"1"64;
"3_G"
$PN"3"52;
"2_N"
$PN"2"60;
%"PICOPROBE_BXA"
"1","(-1600,2200)","4","pure_quanta","I92";
;
LOCATION"J86"
SEC"1"
PART_TYPE"SMLF"
VALUE"DELTA-L 4.0"
MATERIAL"EMPTY"
CDS_LIB"pure_quanta"
CDS_LMAN_SYM_OUTLINE"-150,100,150,-100"
SEC_TYPE""
NEEDS_NO_SIZE"TRUE"
PART_NUMBER"TP33";
"1_P"
$PN"1"60;
"3_G"
$PN"3"53;
"2_N"
$PN"2"64;
%"PICOPROBE_BXA"
"1","(-3475,1500)","0","pure_quanta","I93";
;
LOCATION"J118"
SEC"1"
PART_TYPE"SMLF"
MATERIAL"EMPTY"
VALUE"DELTA-L 4.0"
CDS_LIB"pure_quanta"
CDS_LMAN_SYM_OUTLINE"-150,100,150,-100"
SEC_TYPE""
NEEDS_NO_SIZE"TRUE"
PART_NUMBER"TP33";
"1_P"
$PN"1"62;
"3_G"
$PN"3"55;
"2_N"
$PN"2"63;
%"PICOPROBE_BXA"
"1","(-1575,1550)","4","pure_quanta","I94";
;
LOCATION"J120"
SEC"1"
MATERIAL"EMPTY"
VALUE"DELTA-L 4.0"
PART_TYPE"SMLF"
CDS_LIB"pure_quanta"
CDS_LMAN_SYM_OUTLINE"-150,100,150,-100"
SEC_TYPE""
NEEDS_NO_SIZE"TRUE"
PART_NUMBER"TP33";
"1_P"
$PN"1"63;
"3_G"
$PN"3"54;
"2_N"
$PN"2"62;
%"PICOPROBE_BXA"
"1","(-3475,775)","0","pure_quanta","I95";
;
LOCATION"J119"
SEC"1"
MATERIAL"EMPTY"
VALUE"DELTA-L 4.0"
PART_TYPE"SMLF"
SEC_TYPE""
CDS_LIB"pure_quanta"
CDS_LMAN_SYM_OUTLINE"-150,100,150,-100"
NEEDS_NO_SIZE"TRUE"
PART_NUMBER"TP33";
"1_P"
$PN"1"57;
"3_G"
$PN"3"56;
"2_N"
$PN"2"58;
%"PICOPROBE_BXA"
"1","(-1550,825)","4","pure_quanta","I96";
;
LOCATION"J121"
SEC"1"
MATERIAL"EMPTY"
VALUE"DELTA-L 4.0"
PART_TYPE"SMLF"
NEEDS_NO_SIZE"TRUE"
CDS_LMAN_SYM_OUTLINE"-150,100,150,-100"
CDS_LIB"pure_quanta"
SEC_TYPE""
PART_NUMBER"TP33";
"1_P"
$PN"1"58;
"3_G"
$PN"3"61;
"2_N"
$PN"2"57;
END.
